(kicad_pcb
	(version 20260206)
	(generator "pcbnew")
	(generator_version "10.0")
	(general
		(thickness 1.6)
		(legacy_teardrops no)
	)
	(paper "A4")
	(title_block
		(title "Wiwynn_Tioga_Pass_MB.brd")
		(comment 1 "Tioga Pass / footprints 637-643 of 4770")
	)
	(layers
		(0 "F.Cu" signal "TOP")
		(4 "In1.Cu" signal "L2GND")
		(6 "In2.Cu" signal "L3")
		(8 "In3.Cu" signal "L4GND")
		(10 "In4.Cu" signal "L5")
		(12 "In5.Cu" signal "L6GND")
		(14 "In6.Cu" signal "L7VCC")
		(16 "In7.Cu" signal "L8VCC")
		(18 "In8.Cu" signal "L9GND")
		(20 "In9.Cu" signal "L10")
		(22 "In10.Cu" signal "L11GND")
		(24 "In11.Cu" signal "L12")
		(26 "In12.Cu" signal "L13GND")
		(2 "B.Cu" signal "BOTTOM")
		(9 "F.Adhes" user "F.Adhesive")
		(11 "B.Adhes" user "B.Adhesive")
		(13 "F.Paste" user "Package Geometry/Pastemask Top")
		(15 "B.Paste" user "Package Geometry/Pastemask Bottom")
		(5 "F.SilkS" user "Ref Des/Silkscreen Top")
		(7 "B.SilkS" user "Ref Des/Silkscreen Bottom")
		(1 "F.Mask" user "Board Geometry/Soldermask Top")
		(3 "B.Mask" user "Board Geometry/Soldermask Bottom")
		(17 "Dwgs.User" user "User.Drawings")
		(19 "Cmts.User" user "User.Comments")
		(21 "Eco1.User" user "User.Eco1")
		(23 "Eco2.User" user "User.Eco2")
		(25 "Edge.Cuts" user "Board Geometry/Outline")
		(27 "Margin" user)
		(31 "F.CrtYd" user "Package Geometry/Place Bound Top")
		(29 "B.CrtYd" user "Package Geometry/Place Bound Bottom")
		(35 "F.Fab" user "Ref Des/Assembly Top")
		(33 "B.Fab" user "Ref Des/Assembly Bottom")
	)
	(footprint ""
		(layer "F.Cu")
		(at 439.976006 -41.663874 180)
		(property "Reference" "R25W7"
			(at 0 0 180)
			(layer "F.SilkS")
			(hide yes)
			(effects
				(font
					(size 1.27 1.27)
				)
			)
		)
		(property "Value" "*"
			(at 0.064008 -4.108196 180)
			(unlocked yes)
			(layer "F.Fab")
			(hide yes)
			(effects
				(font
					(size 1.27 1.016)
					(thickness 0.1524)
				)
			)
		)
		(property "Device Type" "120R2F-GP_RCL_GP-120R2F-GP,64.A"
			(at 0.064008 -5.632196 180)
			(unlocked yes)
			(layer "F.Fab")
			(hide yes)
			(effects
				(font
					(size 1.27 1.016)
					(thickness 0.1524)
				)
			)
		)
		(duplicate_pad_numbers_are_jumpers no)
		(fp_line
			(start 0.508 -0.9398)
			(end -0.508 -0.9398)
			(stroke
				(width 0.1524)
				(type default)
			)
			(layer "F.SilkS")
		)
		(fp_line
			(start -0.508 -0.9398)
			(end -0.508 0.9398)
			(stroke
				(width 0.1524)
				(type default)
			)
			(layer "F.SilkS")
		)
		(fp_rect
			(start -0.508 0.9398)
			(end 0.508 -0.9398)
			(stroke
				(width 0)
				(type default)
			)
			(fill no)
			(layer "F.CrtYd")
		)
		(fp_rect
			(start -0.508 0.9398)
			(end 0.508 -0.9398)
			(stroke
				(width 0)
				(type default)
			)
			(fill no)
			(layer "F.Fab")
		)
		(pad "1" smd custom
			(at 0 -0.4445 180)
			(size 0.1397 0.1397)
			(layers "F.Cu" "F.Mask" "F.Paste")
			(net "GND")
			(options
				(clearance outline)
				(anchor circle)
			)
			(primitives
				(gr_poly
					(pts
						(arc
							(start -0.1778 -0.2794)
							(mid -0.249642 -0.249642)
							(end -0.2794 -0.1778)
						)
						(arc
							(start -0.2794 0.1778)
							(mid -0.249642 0.249642)
							(end -0.1778 0.2794)
						)
						(arc
							(start 0.1778 0.2794)
							(mid 0.249642 0.249642)
							(end 0.2794 0.1778)
						)
						(arc
							(start 0.2794 -0.1778)
							(mid 0.249642 -0.249642)
							(end 0.1778 -0.2794)
						)
					)
					(width 0)
					(fill yes)
				)
			)
		)
		(pad "2" smd custom
			(at 0 0.4445 180)
			(size 0.1397 0.1397)
			(layers "F.Cu" "F.Mask" "F.Paste")
			(net "BMC_M_CAS_N")
			(options
				(clearance outline)
				(anchor circle)
			)
			(primitives
				(gr_poly
					(pts
						(arc
							(start -0.1778 -0.2794)
							(mid -0.249642 -0.249642)
							(end -0.2794 -0.1778)
						)
						(arc
							(start -0.2794 0.1778)
							(mid -0.249642 0.249642)
							(end -0.1778 0.2794)
						)
						(arc
							(start 0.1778 0.2794)
							(mid 0.249642 0.249642)
							(end 0.2794 0.1778)
						)
						(arc
							(start 0.2794 -0.1778)
							(mid 0.249642 -0.249642)
							(end 0.1778 -0.2794)
						)
					)
					(width 0)
					(fill yes)
				)
			)
		)
	)
	(footprint ""
		(layer "F.Cu")
		(at 266.397232 -12.954 90)
		(property "Reference" "C5G5"
			(at 1.848866 0.752348 90)
			(unlocked yes)
			(layer "F.SilkS")
			(effects
				(font
					(size 1.27 0.9652)
					(thickness 0.1524)
				)
			)
		)
		(property "Value" ""
			(at 0 0 90)
			(layer "F.Fab")
			(effects
				(font
					(size 1.27 1.27)
				)
			)
		)
		(duplicate_pad_numbers_are_jumpers no)
		(fp_rect
			(start -0.500126 1.598422)
			(end 0.500126 -0.201422)
			(stroke
				(width 0)
				(type default)
			)
			(fill no)
			(layer "F.CrtYd")
		)
		(fp_line
			(start 0.500126 -0.201422)
			(end 0.500126 1.598422)
			(stroke
				(width 0.1)
				(type default)
			)
			(layer "F.Fab")
		)
		(fp_line
			(start -0.500126 -0.201422)
			(end 0.500126 -0.201422)
			(stroke
				(width 0.1)
				(type default)
			)
			(layer "F.Fab")
		)
		(fp_line
			(start 0.500126 1.598422)
			(end -0.500126 1.598422)
			(stroke
				(width 0.1)
				(type default)
			)
			(layer "F.Fab")
		)
		(fp_line
			(start -0.500126 1.598422)
			(end -0.500126 -0.201422)
			(stroke
				(width 0.1)
				(type default)
			)
			(layer "F.Fab")
		)
		(pad "1" smd rect
			(at 0 0)
			(size 0.889 0.9906)
			(layers "F.Cu" "F.Mask" "F.Paste")
			(net "PVDDQ_ABC")
		)
		(pad "2" smd rect
			(at 0 1.397)
			(size 0.889 0.9906)
			(layers "F.Cu" "F.Mask" "F.Paste")
			(net "GND")
		)
		(zone
			(layer "F.Cu")
			(hatch none 0.5)
			(connect_pads
				(clearance 0)
			)
			(min_thickness 0.25)
			(keepout
				(tracks not_allowed)
				(vias allowed)
				(pads allowed)
				(copperpour not_allowed)
				(footprints allowed)
			)
			(placement
				(enabled no)
				(sheetname "")
			)
			(fill
				(thermal_gap 0.5)
				(thermal_bridge_width 0.5)
				(island_removal_mode 0)
			)
			(polygon
				(pts
					(xy 267.349732 -12.4587) (xy 267.349732 -13.4493) (xy 266.841732 -13.4493) (xy 266.841732 -12.4587)
				)
			)
		)
		(zone
			(layer "F.Cu")
			(hatch none 0.5)
			(connect_pads
				(clearance 0)
			)
			(min_thickness 0.25)
			(keepout
				(tracks allowed)
				(vias not_allowed)
				(pads allowed)
				(copperpour not_allowed)
				(footprints allowed)
			)
			(placement
				(enabled no)
				(sheetname "")
			)
			(fill
				(thermal_gap 0.5)
				(thermal_bridge_width 0.5)
				(island_removal_mode 0)
			)
			(polygon
				(pts
					(xy 267.349732 -12.4587) (xy 267.349732 -13.4493) (xy 266.841732 -13.4493) (xy 266.841732 -12.4587)
				)
			)
		)
	)
	(footprint ""
		(layer "F.Cu")
		(at 451.358 -28.7655)
		(property "Reference" "C25W2"
			(at -0.8382 -0.67818 0)
			(unlocked yes)
			(layer "F.SilkS")
			(effects
				(font
					(size 0.4064 0.254)
					(thickness 0.1524)
				)
				(justify left)
			)
		)
		(property "Value" ""
			(at 0 0 0)
			(layer "F.Fab")
			(effects
				(font
					(size 1.27 1.27)
				)
			)
		)
		(duplicate_pad_numbers_are_jumpers no)
		(fp_poly
			(pts
				(xy 0.3048 -0.1016) (xy 0.3048 0.9906) (xy -0.3048 0.9906) (xy -0.3048 -0.1016)
			)
			(stroke
				(width 0)
				(type default)
			)
			(fill no)
			(layer "F.CrtYd")
		)
		(fp_line
			(start -0.3048 -0.1016)
			(end -0.3048 0.9906)
			(stroke
				(width 0.1)
				(type default)
			)
			(layer "F.Fab")
		)
		(fp_line
			(start -0.3048 0.9906)
			(end 0.3048 0.9906)
			(stroke
				(width 0.1)
				(type default)
			)
			(layer "F.Fab")
		)
		(fp_line
			(start 0.3048 -0.1016)
			(end -0.3048 -0.1016)
			(stroke
				(width 0.1)
				(type default)
			)
			(layer "F.Fab")
		)
		(fp_line
			(start 0.3048 0.9906)
			(end 0.3048 -0.1016)
			(stroke
				(width 0.1)
				(type default)
			)
			(layer "F.Fab")
		)
		(pad "1" smd rect
			(at 0 0)
			(size 0.508 0.508)
			(layers "F.Cu" "F.Mask" "F.Paste")
			(net "P1V2_AUX_BMC")
		)
		(pad "2" smd rect
			(at 0 0.889)
			(size 0.508 0.508)
			(layers "F.Cu" "F.Mask" "F.Paste")
			(net "GND")
		)
		(zone
			(layer "F.Cu")
			(hatch none 0.5)
			(connect_pads
				(clearance 0)
			)
			(min_thickness 0.25)
			(keepout
				(tracks allowed)
				(vias not_allowed)
				(pads allowed)
				(copperpour not_allowed)
				(footprints allowed)
			)
			(placement
				(enabled no)
				(sheetname "")
			)
			(fill
				(thermal_gap 0.5)
				(thermal_bridge_width 0.5)
				(island_removal_mode 0)
			)
			(polygon
				(pts
					(xy 451.104 -28.5115) (xy 451.612 -28.5115) (xy 451.612 -28.1305) (xy 451.104 -28.1305)
				)
			)
		)
		(zone
			(layer "F.Cu")
			(hatch none 0.5)
			(connect_pads
				(clearance 0)
			)
			(min_thickness 0.25)
			(keepout
				(tracks not_allowed)
				(vias allowed)
				(pads allowed)
				(copperpour not_allowed)
				(footprints allowed)
			)
			(placement
				(enabled no)
				(sheetname "")
			)
			(fill
				(thermal_gap 0.5)
				(thermal_bridge_width 0.5)
				(island_removal_mode 0)
			)
			(polygon
				(pts
					(xy 451.104 -28.1305) (xy 451.612 -28.1305) (xy 451.612 -28.5115) (xy 451.104 -28.5115)
				)
			)
		)
	)
	(footprint ""
		(layer "F.Cu")
		(at 337.429602 -120.038368 90)
		(property "Reference" "C6B16"
			(at -0.8382 -0.67818 90)
			(unlocked yes)
			(layer "F.SilkS")
			(effects
				(font
					(size 0.4064 0.254)
					(thickness 0.1524)
				)
				(justify left)
			)
		)
		(property "Value" ""
			(at 0 0 90)
			(layer "F.Fab")
			(effects
				(font
					(size 1.27 1.27)
				)
			)
		)
		(duplicate_pad_numbers_are_jumpers no)
		(fp_poly
			(pts
				(xy 0.3048 -0.1016) (xy 0.3048 0.9906) (xy -0.3048 0.9906) (xy -0.3048 -0.1016)
			)
			(stroke
				(width 0)
				(type default)
			)
			(fill no)
			(layer "F.CrtYd")
		)
		(fp_line
			(start 0.3048 -0.1016)
			(end -0.3048 -0.1016)
			(stroke
				(width 0.1)
				(type default)
			)
			(layer "F.Fab")
		)
		(fp_line
			(start -0.3048 -0.1016)
			(end -0.3048 0.9906)
			(stroke
				(width 0.1)
				(type default)
			)
			(layer "F.Fab")
		)
		(fp_line
			(start 0.3048 0.9906)
			(end 0.3048 -0.1016)
			(stroke
				(width 0.1)
				(type default)
			)
			(layer "F.Fab")
		)
		(fp_line
			(start -0.3048 0.9906)
			(end 0.3048 0.9906)
			(stroke
				(width 0.1)
				(type default)
			)
			(layer "F.Fab")
		)
		(pad "1" smd rect
			(at 0 0 90)
			(size 0.508 0.508)
			(layers "F.Cu" "F.Mask" "F.Paste")
			(net "P3E_CPU0_PE1_PCH_TXP<10>")
		)
		(pad "2" smd rect
			(at 0 0.889 90)
			(size 0.508 0.508)
			(layers "F.Cu" "F.Mask" "F.Paste")
			(net "P3E_CPU0_PE1_PCH_C_TXP<10>")
		)
		(zone
			(layer "F.Cu")
			(hatch none 0.5)
			(connect_pads
				(clearance 0)
			)
			(min_thickness 0.25)
			(keepout
				(tracks allowed)
				(vias not_allowed)
				(pads allowed)
				(copperpour not_allowed)
				(footprints allowed)
			)
			(placement
				(enabled no)
				(sheetname "")
			)
			(fill
				(thermal_gap 0.5)
				(thermal_bridge_width 0.5)
				(island_removal_mode 0)
			)
			(polygon
				(pts
					(xy 337.683602 -119.784368) (xy 337.683602 -120.292368) (xy 338.064602 -120.292368) (xy 338.064602 -119.784368)
				)
			)
		)
		(zone
			(layer "F.Cu")
			(hatch none 0.5)
			(connect_pads
				(clearance 0)
			)
			(min_thickness 0.25)
			(keepout
				(tracks not_allowed)
				(vias allowed)
				(pads allowed)
				(copperpour not_allowed)
				(footprints allowed)
			)
			(placement
				(enabled no)
				(sheetname "")
			)
			(fill
				(thermal_gap 0.5)
				(thermal_bridge_width 0.5)
				(island_removal_mode 0)
			)
			(polygon
				(pts
					(xy 338.064602 -119.784368) (xy 338.064602 -120.292368) (xy 337.683602 -120.292368) (xy 337.683602 -119.784368)
				)
			)
		)
	)
	(footprint ""
		(layer "F.Cu")
		(at 13.335 -101.981)
		(property "Reference" "R1C9"
			(at 0 0 0)
			(layer "F.SilkS")
			(hide yes)
			(effects
				(font
					(size 1.27 1.27)
				)
			)
		)
		(property "Value" ""
			(at 0 0 0)
			(layer "F.Fab")
			(effects
				(font
					(size 1.27 1.27)
				)
			)
		)
		(duplicate_pad_numbers_are_jumpers no)
		(fp_poly
			(pts
				(xy -0.2794 -0.1016) (xy 0.2794 -0.1016) (xy 0.2794 0.9906) (xy -0.2794 0.9906)
			)
			(stroke
				(width 0)
				(type default)
			)
			(fill no)
			(layer "F.CrtYd")
		)
		(fp_line
			(start -0.2794 -0.1016)
			(end -0.2794 0.9906)
			(stroke
				(width 0.1)
				(type default)
			)
			(layer "F.Fab")
		)
		(fp_line
			(start -0.2794 0.9906)
			(end 0.2794 0.9906)
			(stroke
				(width 0.1)
				(type default)
			)
			(layer "F.Fab")
		)
		(fp_line
			(start 0.2794 -0.1016)
			(end -0.2794 -0.1016)
			(stroke
				(width 0.1)
				(type default)
			)
			(layer "F.Fab")
		)
		(fp_line
			(start 0.2794 0.9906)
			(end 0.2794 -0.1016)
			(stroke
				(width 0.1)
				(type default)
			)
			(layer "F.Fab")
		)
		(pad "1" smd rect
			(at 0 0)
			(size 0.508 0.508)
			(layers "F.Cu" "F.Mask" "F.Paste")
			(net "IRQ_BOARD_BMC_ALERT_N")
		)
		(pad "2" smd rect
			(at 0 0.889)
			(size 0.508 0.508)
			(layers "F.Cu" "F.Mask" "F.Paste")
			(net "FAN_TACH2_R")
		)
		(zone
			(layer "F.Cu")
			(hatch none 0.5)
			(connect_pads
				(clearance 0)
			)
			(min_thickness 0.25)
			(keepout
				(tracks allowed)
				(vias not_allowed)
				(pads allowed)
				(copperpour not_allowed)
				(footprints allowed)
			)
			(placement
				(enabled no)
				(sheetname "")
			)
			(fill
				(thermal_gap 0.5)
				(thermal_bridge_width 0.5)
				(island_removal_mode 0)
			)
			(polygon
				(pts
					(xy 13.081 -101.727) (xy 13.589 -101.727) (xy 13.589 -101.346) (xy 13.081 -101.346)
				)
			)
		)
		(zone
			(layer "F.Cu")
			(hatch none 0.5)
			(connect_pads
				(clearance 0)
			)
			(min_thickness 0.25)
			(keepout
				(tracks not_allowed)
				(vias allowed)
				(pads allowed)
				(copperpour not_allowed)
				(footprints allowed)
			)
			(placement
				(enabled no)
				(sheetname "")
			)
			(fill
				(thermal_gap 0.5)
				(thermal_bridge_width 0.5)
				(island_removal_mode 0)
			)
			(polygon
				(pts
					(xy 13.081 -101.346) (xy 13.589 -101.346) (xy 13.589 -101.727) (xy 13.081 -101.727)
				)
			)
		)
	)
	(footprint ""
		(layer "F.Cu")
		(at 434.37048 -43.844464 -90)
		(property "Reference" "R9F33"
			(at 0 0 270)
			(layer "F.SilkS")
			(hide yes)
			(effects
				(font
					(size 1.27 1.27)
				)
			)
		)
		(property "Value" ""
			(at 0 0 270)
			(layer "F.Fab")
			(effects
				(font
					(size 1.27 1.27)
				)
			)
		)
		(duplicate_pad_numbers_are_jumpers no)
		(fp_poly
			(pts
				(xy -0.2794 -0.1016) (xy 0.2794 -0.1016) (xy 0.2794 0.9906) (xy -0.2794 0.9906)
			)
			(stroke
				(width 0)
				(type default)
			)
			(fill no)
			(layer "F.CrtYd")
		)
		(fp_line
			(start -0.2794 0.9906)
			(end 0.2794 0.9906)
			(stroke
				(width 0.1)
				(type default)
			)
			(layer "F.Fab")
		)
		(fp_line
			(start 0.2794 0.9906)
			(end 0.2794 -0.1016)
			(stroke
				(width 0.1)
				(type default)
			)
			(layer "F.Fab")
		)
		(fp_line
			(start -0.2794 -0.1016)
			(end -0.2794 0.9906)
			(stroke
				(width 0.1)
				(type default)
			)
			(layer "F.Fab")
		)
		(fp_line
			(start 0.2794 -0.1016)
			(end -0.2794 -0.1016)
			(stroke
				(width 0.1)
				(type default)
			)
			(layer "F.Fab")
		)
		(pad "1" smd rect
			(at 0 0 270)
			(size 0.508 0.508)
			(layers "F.Cu" "F.Mask" "F.Paste")
			(net "PECI_BMC")
		)
		(pad "2" smd rect
			(at 0 0.889 270)
			(size 0.508 0.508)
			(layers "F.Cu" "F.Mask" "F.Paste")
			(net "PECI_BMC_R")
		)
		(zone
			(layer "F.Cu")
			(hatch none 0.5)
			(connect_pads
				(clearance 0)
			)
			(min_thickness 0.25)
			(keepout
				(tracks not_allowed)
				(vias allowed)
				(pads allowed)
				(copperpour not_allowed)
				(footprints allowed)
			)
			(placement
				(enabled no)
				(sheetname "")
			)
			(fill
				(thermal_gap 0.5)
				(thermal_bridge_width 0.5)
				(island_removal_mode 0)
			)
			(polygon
				(pts
					(xy 433.73548 -44.098464) (xy 433.73548 -43.590464) (xy 434.11648 -43.590464) (xy 434.11648 -44.098464)
				)
			)
		)
		(zone
			(layer "F.Cu")
			(hatch none 0.5)
			(connect_pads
				(clearance 0)
			)
			(min_thickness 0.25)
			(keepout
				(tracks allowed)
				(vias not_allowed)
				(pads allowed)
				(copperpour not_allowed)
				(footprints allowed)
			)
			(placement
				(enabled no)
				(sheetname "")
			)
			(fill
				(thermal_gap 0.5)
				(thermal_bridge_width 0.5)
				(island_removal_mode 0)
			)
			(polygon
				(pts
					(xy 434.11648 -44.098464) (xy 434.11648 -43.590464) (xy 433.73548 -43.590464) (xy 433.73548 -44.098464)
				)
			)
		)
	)
	(footprint ""
		(layer "F.Cu")
		(at 426.5295 -130.556 -90)
		(property "Reference" "R8B6"
			(at 0 0 270)
			(layer "F.SilkS")
			(hide yes)
			(effects
				(font
					(size 1.27 1.27)
				)
			)
		)
		(property "Value" ""
			(at 0 0 270)
			(layer "F.Fab")
			(effects
				(font
					(size 1.27 1.27)
				)
			)
		)
		(duplicate_pad_numbers_are_jumpers no)
		(fp_poly
			(pts
				(xy -0.2794 -0.1016) (xy 0.2794 -0.1016) (xy 0.2794 0.9906) (xy -0.2794 0.9906)
			)
			(stroke
				(width 0)
				(type default)
			)
			(fill no)
			(layer "F.CrtYd")
		)
		(fp_line
			(start -0.2794 0.9906)
			(end 0.2794 0.9906)
			(stroke
				(width 0.1)
				(type default)
			)
			(layer "F.Fab")
		)
		(fp_line
			(start 0.2794 0.9906)
			(end 0.2794 -0.1016)
			(stroke
				(width 0.1)
				(type default)
			)
			(layer "F.Fab")
		)
		(fp_line
			(start -0.2794 -0.1016)
			(end -0.2794 0.9906)
			(stroke
				(width 0.1)
				(type default)
			)
			(layer "F.Fab")
		)
		(fp_line
			(start 0.2794 -0.1016)
			(end -0.2794 -0.1016)
			(stroke
				(width 0.1)
				(type default)
			)
			(layer "F.Fab")
		)
		(pad "1" smd rect
			(at 0 0 270)
			(size 0.508 0.508)
			(layers "F.Cu" "F.Mask" "F.Paste")
			(net "PVPP_ABC")
		)
		(pad "2" smd rect
			(at 0 0.889 270)
			(size 0.508 0.508)
			(layers "F.Cu" "F.Mask" "F.Paste")
			(net "SMB_HFI0_CPU0_LVC2_SCL")
		)
		(zone
			(layer "F.Cu")
			(hatch none 0.5)
			(connect_pads
				(clearance 0)
			)
			(min_thickness 0.25)
			(keepout
				(tracks not_allowed)
				(vias allowed)
				(pads allowed)
				(copperpour not_allowed)
				(footprints allowed)
			)
			(placement
				(enabled no)
				(sheetname "")
			)
			(fill
				(thermal_gap 0.5)
				(thermal_bridge_width 0.5)
				(island_removal_mode 0)
			)
			(polygon
				(pts
					(xy 425.8945 -130.81) (xy 425.8945 -130.302) (xy 426.2755 -130.302) (xy 426.2755 -130.81)
				)
			)
		)
		(zone
			(layer "F.Cu")
			(hatch none 0.5)
			(connect_pads
				(clearance 0)
			)
			(min_thickness 0.25)
			(keepout
				(tracks allowed)
				(vias not_allowed)
				(pads allowed)
				(copperpour not_allowed)
				(footprints allowed)
			)
			(placement
				(enabled no)
				(sheetname "")
			)
			(fill
				(thermal_gap 0.5)
				(thermal_bridge_width 0.5)
				(island_removal_mode 0)
			)
			(polygon
				(pts
					(xy 426.2755 -130.81) (xy 426.2755 -130.302) (xy 425.8945 -130.302) (xy 425.8945 -130.81)
				)
			)
		)
	)
)
